FILE_TYPE = MACRO_DRAWING;
SET COLOR_WIRE YELLOW;
SET COLOR_PROP ORANGE;
SET COLOR_DOT WHITE;
SET COLOR_ARC YELLOW;
SET COLOR_BODY GREEN;
SET COLOR_NOTE PURPLE;
SET PROP_DISPLAY VALUE;
SET PAGE_NUMBER P1;
FORCEADD QUANTA_TITLE_BLOCK_C..1
(6525 -2000);
FORCEPROP 1 LAST CUSTOM_TXT_CDS <CON_LAST_MODIFIED>
J 0
(4640 -1985);
DISPLAY 0.978723 (4640 -1985);
FORCEPROP 2 LAST CUSTOM_TXT_CDS <XR_PAGE_TITLE>
J 0
(-1365 3250);
DISPLAY 0.638298 (-1365 3250);
PAINT PINK (-1365 3250);
DISPLAY INVISIBLE (-1365 3250);
FORCEPROP 1 LAST CUSTOM_TXT_CDS <NAME_2>
J 0
(3350 -1950);
FORCEPROP 1 LAST CUSTOM_TXT_CDS <NAME_1>
J 0
(3350 -1825);
FORCEPROP 1 LAST CUSTOM_TXT_CDS <Q_NUMBER>
J 0
(5122 -1897);
DISPLAY 1.212766 (5122 -1897);
FORCEPROP 1 LAST CUSTOM_TXT_CDS <Q_PROJ>
J 0
(4143 -1898);
DISPLAY 1.212766 (4143 -1898);
FORCEPROP 1 LAST CUSTOM_TXT_CDS <Q_REV>
J 0
(6341 -1897);
DISPLAY 1.212766 (6341 -1897);
FORCEPROP 1 LAST CUSTOM_TXT_CDS <CON_PAGE_NUM> OF <CON_TOTAL_PAGES>
J 0
(6079 -1982);
DISPLAY 0.978723 (6079 -1982);
FORCEPROP 1 LAST Q_TITLE COVER PAGE
J 0
(-2841 -1974);
DISPLAY 2.446809 (-2841 -1974);
PAINT GREEN (-2841 -1974);
FORCEPROP 1 LAST Q_DEPT 
J 1
(2762 -1951);
DISPLAY 1.957447 (2762 -1951);
PAINT GREEN (2762 -1951);
FORCEPROP 2 LAST CDS_XR_PAGE_TITLE CR-1 : @S9S_MB_2U_LIB.S9S_MB_2U(SCH_1):PAGE1
J 0
(-1365 3250);
DISPLAY 0.638298 (-1365 3250);
PAINT PINK (-1365 3250);
DISPLAY INVISIBLE (-1365 3250);
FORCEPROP 1 LAST COMMENT_BODY TRUE
J 0
(6537 -2013);
DISPLAY 0.978723 (6537 -2013);
PAINT GREEN (6537 -2013);
DISPLAY INVISIBLE (6537 -2013);
FORCEPROP 2 LAST PAGE_BORDER TRUE
J 0
(-1365 3250);
DISPLAY 0.638298 (-1365 3250);
PAINT PINK (-1365 3250);
DISPLAY INVISIBLE (-1365 3250);
FORCEPROP 1 LAST CDS_LMAN_SYM_OUTLINE -9475,6775,100,-125
J 0
(6525 -2000);
DISPLAY 0.468085 (6525 -2000);
PAINT GREEN (6525 -2000);
DISPLAY INVISIBLE (6525 -2000);
FORCEPROP 2 LAST CDS_LIB pure_quanta
J 0
(6525 -2000);
PAINT MONO (6525 -2000);
DISPLAY INVISIBLE (6525 -2000);
FORCEPROP 0 LAST CDS_CON_LAST_MODIFIED Thu Aug 24 16:11:55 2023
J 0
(4640 -1985);
PAINT MONO (4640 -1985);
DISPLAY INVISIBLE (4640 -1985);
FORCENOTE
MB
(1450 775) 0;
DISPLAY LEFT (1450 775);
DISPLAY 8.723404 (1450 775);
PAINT SKYBLUE (1450 775);
FORCENOTE
GRAND TETON
(-300 1950) 0;
DISPLAY LEFT (-300 1950);
DISPLAY 8.723404 (-300 1950);
PAINT SKYBLUE (-300 1950);
QUIT
